(kicad_pcb
	(version 20241229)
	(generator "pcbnew")
	(generator_version "9.0")
	(general
		(thickness 1.711)
		(legacy_teardrops no)
	)
	(paper "A4")
	(title_block
		(title "Antmicro Baseboard for Jetson AGX Thor")
		(date "2026-02-18")
		(rev "1.1.0")
		(company "Antmicro Ltd")
		(comment 1 "www.antmicro.com")
		(comment 9 "footprints 663-667 of 1170")
	)
	(layers
		(0 "F.Cu" signal)
		(4 "In1.Cu" signal)
		(6 "In2.Cu" signal)
		(8 "In3.Cu" signal)
		(10 "In4.Cu" jumper)
		(12 "In5.Cu" signal)
		(14 "In6.Cu" signal)
		(16 "In7.Cu" signal)
		(18 "In8.Cu" signal)
		(2 "B.Cu" signal)
		(9 "F.Adhes" user "F.Adhesive")
		(11 "B.Adhes" user "B.Adhesive")
		(13 "F.Paste" user)
		(15 "B.Paste" user)
		(5 "F.SilkS" user "F.Silkscreen")
		(7 "B.SilkS" user "B.Silkscreen")
		(1 "F.Mask" user)
		(3 "B.Mask" user)
		(17 "Dwgs.User" user "User.Drawings")
		(19 "Cmts.User" user "User.Comments")
		(21 "Eco1.User" user "User.Eco1")
		(23 "Eco2.User" user "User.Eco2")
		(25 "Edge.Cuts" user)
		(27 "Margin" user)
		(31 "F.CrtYd" user "F.Courtyard")
		(29 "B.CrtYd" user "B.Courtyard")
		(35 "F.Fab" user)
		(33 "B.Fab" user)
	)
	(footprint "antmicro-footprints:TP_SMD_0.75mm"
		(layer "B.Cu")
		(at 217.39 92.322 -90)
		(property "Reference" "TP18"
			(at 0.44 -3.3 0)
			(layer "B.SilkS")
			(effects
				(font
					(size 0.7 0.7)
					(thickness 0.15)
				)
				(justify left bottom mirror)
			)
		)
		(property "Value" "TP_0.75mm_SMD"
			(at 0 -1.2 90)
			(layer "B.Fab")
			(effects
				(font
					(size 0.7 0.7)
					(thickness 0.15)
				)
				(justify left bottom mirror)
			)
		)
		(property "Description" "SMT test point"
			(at 0 0 90)
			(layer "B.Fab")
			(hide yes)
			(effects
				(font
					(size 1.27 1.27)
					(thickness 0.15)
				)
				(justify mirror)
			)
		)
		(property "MPN" ""
			(at 0 0 90)
			(unlocked yes)
			(layer "B.Fab")
			(hide yes)
			(effects
				(font
					(size 1 1)
					(thickness 0.15)
				)
				(justify mirror)
			)
		)
		(property "Manufacturer" ""
			(at 0 0 90)
			(unlocked yes)
			(layer "B.Fab")
			(hide yes)
			(effects
				(font
					(size 1 1)
					(thickness 0.15)
				)
				(justify mirror)
			)
		)
		(property "Author" "Antmicro"
			(at 0 0 90)
			(unlocked yes)
			(layer "B.Fab")
			(hide yes)
			(effects
				(font
					(size 1 1)
					(thickness 0.15)
				)
				(justify mirror)
			)
		)
		(property "License" "Apache-2.0"
			(at 0 0 90)
			(unlocked yes)
			(layer "B.Fab")
			(hide yes)
			(effects
				(font
					(size 1 1)
					(thickness 0.15)
				)
				(justify mirror)
			)
		)
		(sheetname "/USB DP Alt mode/")
		(sheetfile "usb_dp.kicad_sch")
		(attr exclude_from_pos_files exclude_from_bom)
		(fp_circle
			(center 0 0)
			(end 0.475 0)
			(stroke
				(width 0.05)
				(type default)
			)
			(fill no)
			(layer "B.CrtYd")
		)
		(fp_text user "License: Apache-2.0"
			(at -0.4 -5.101 90)
			(layer "B.Fab")
			(effects
				(font
					(size 0.7 0.7)
					(thickness 0.15)
				)
				(justify left bottom mirror)
			)
		)
		(fp_text user "Author: Antmicro"
			(at -0.4 -3.901 90)
			(layer "B.Fab")
			(effects
				(font
					(size 0.7 0.7)
					(thickness 0.15)
				)
				(justify left bottom mirror)
			)
		)
		(fp_text user "${REFERENCE}"
			(at -0.4 -2.7 90)
			(layer "B.Fab")
			(effects
				(font
					(size 0.7 0.7)
					(thickness 0.15)
				)
				(justify left bottom mirror)
			)
		)
		(pad "1" smd circle
			(at 0 -0.01 270)
			(size 0.75 0.75)
			(layers "B.Cu" "B.Mask")
			(net 1044 "Net-(U33-CAD_SNK{slash}RSVD1)")
			(pinfunction "1")
			(pintype "passive")
		)
	)
	(footprint "antmicro-footprints:C_0402_1005Metric"
		(layer "B.Cu")
		(at 197.626 139.8)
		(descr "Capacitor SMD 0402")
		(tags "capacitor SMD 0402")
		(property "Reference" "C176"
			(at -1.3 0.7 0)
			(layer "B.SilkS")
			(effects
				(font
					(size 0.7 0.7)
					(thickness 0.15)
				)
				(justify right top mirror)
			)
		)
		(property "Value" "C_100n_0402"
			(at -1.022927 -2.155213 0)
			(layer "B.Fab")
			(effects
				(font
					(size 0.7 0.7)
					(thickness 0.15)
				)
				(justify right top mirror)
			)
		)
		(property "Datasheet" "https://www.murata.com/products/productdetail?partno=GRM155R61H104KE14%23"
			(at 0 0 0)
			(layer "B.Fab")
			(hide yes)
			(effects
				(font
					(size 1.27 1.27)
					(thickness 0.15)
				)
				(justify mirror)
			)
		)
		(property "Description" "SMD Multilayer Ceramic Capacitor, 0.1 µF, 50 V, 0402 [1005 Metric], ± 10%, X5R, GRM Series"
			(at 0 0 0)
			(layer "B.Fab")
			(hide yes)
			(effects
				(font
					(size 1.27 1.27)
					(thickness 0.15)
				)
				(justify mirror)
			)
		)
		(property "MPN" "GRM155R61H104KE14D"
			(at 0 0 180)
			(unlocked yes)
			(layer "B.Fab")
			(hide yes)
			(effects
				(font
					(size 1 1)
					(thickness 0.15)
				)
				(justify mirror)
			)
		)
		(property "Manufacturer" "Murata"
			(at 0 0 180)
			(unlocked yes)
			(layer "B.Fab")
			(hide yes)
			(effects
				(font
					(size 1 1)
					(thickness 0.15)
				)
				(justify mirror)
			)
		)
		(property "License" "Apache-2.0"
			(at 0 0 180)
			(unlocked yes)
			(layer "B.Fab")
			(hide yes)
			(effects
				(font
					(size 1 1)
					(thickness 0.15)
				)
				(justify mirror)
			)
		)
		(property "Author" "Antmicro"
			(at 0 0 180)
			(unlocked yes)
			(layer "B.Fab")
			(hide yes)
			(effects
				(font
					(size 1 1)
					(thickness 0.15)
				)
				(justify mirror)
			)
		)
		(property "Val" "100n"
			(at 0 0 180)
			(unlocked yes)
			(layer "B.Fab")
			(hide yes)
			(effects
				(font
					(size 1 1)
					(thickness 0.15)
				)
				(justify mirror)
			)
		)
		(property "Voltage" "50V"
			(at 0 0 180)
			(unlocked yes)
			(layer "B.Fab")
			(hide yes)
			(effects
				(font
					(size 1 1)
					(thickness 0.15)
				)
				(justify mirror)
			)
		)
		(property "Dielectric" "X5R"
			(at 0 0 180)
			(unlocked yes)
			(layer "B.Fab")
			(hide yes)
			(effects
				(font
					(size 1 1)
					(thickness 0.15)
				)
				(justify mirror)
			)
		)
		(sheetname "/SFP/")
		(sheetfile "sfp.kicad_sch")
		(attr smd)
		(fp_rect
			(start -0.925 0.47)
			(end 0.925 -0.47)
			(stroke
				(width 0.05)
				(type default)
			)
			(fill no)
			(layer "B.CrtYd")
		)
		(fp_line
			(start -0.494 -0.248)
			(end -0.494 0.25)
			(stroke
				(width 0.15)
				(type solid)
			)
			(layer "B.Fab")
		)
		(fp_line
			(start -0.494 0.25)
			(end 0.504 0.25)
			(stroke
				(width 0.15)
				(type solid)
			)
			(layer "B.Fab")
		)
		(fp_line
			(start 0.504 -0.248)
			(end -0.494 -0.248)
			(stroke
				(width 0.15)
				(type solid)
			)
			(layer "B.Fab")
		)
		(fp_line
			(start 0.504 0.25)
			(end 0.504 -0.248)
			(stroke
				(width 0.15)
				(type solid)
			)
			(layer "B.Fab")
		)
		(fp_text user "License: Apache-2.0"
			(at -0.939 -5.799 0)
			(layer "B.Fab")
			(effects
				(font
					(size 0.7 0.7)
					(thickness 0.15)
				)
				(justify right top mirror)
			)
		)
		(fp_text user "Author: Antmicro"
			(at -0.939 -3.399 0)
			(layer "B.Fab")
			(effects
				(font
					(size 0.7 0.7)
					(thickness 0.15)
				)
				(justify right top mirror)
			)
		)
		(fp_text user "${REFERENCE}"
			(at -0.939 -4.599 0)
			(layer "B.Fab")
			(effects
				(font
					(size 0.7 0.7)
					(thickness 0.15)
				)
				(justify right top mirror)
			)
		)
		(pad "1" smd roundrect
			(at -0.48 0)
			(size 0.59 0.64)
			(layers "B.Cu" "B.Mask" "B.Paste")
			(roundrect_rratio 0.25)
			(net 1 "GND")
			(pintype "passive")
		)
		(pad "2" smd roundrect
			(at 0.48 0)
			(size 0.59 0.64)
			(layers "B.Cu" "B.Mask" "B.Paste")
			(roundrect_rratio 0.25)
			(net 379 "/SFP/SH")
			(pintype "passive")
		)
	)
	(footprint "antmicro-footprints:TP_SMD_0.75mm"
		(layer "B.Cu")
		(at 155.5 110 -90)
		(property "Reference" "TP88"
			(at 0 0.6 90)
			(layer "B.SilkS")
			(effects
				(font
					(size 0.7 0.7)
					(thickness 0.15)
				)
				(justify left bottom mirror)
			)
		)
		(property "Value" "TP_0.75mm_SMD"
			(at 0 -1.2 90)
			(layer "B.Fab")
			(effects
				(font
					(size 0.7 0.7)
					(thickness 0.15)
				)
				(justify left bottom mirror)
			)
		)
		(property "Description" "SMT test point"
			(at 0 0 90)
			(layer "B.Fab")
			(hide yes)
			(effects
				(font
					(size 1.27 1.27)
					(thickness 0.15)
				)
				(justify mirror)
			)
		)
		(property "MPN" ""
			(at 0 0 90)
			(unlocked yes)
			(layer "B.Fab")
			(hide yes)
			(effects
				(font
					(size 1 1)
					(thickness 0.15)
				)
				(justify mirror)
			)
		)
		(property "Manufacturer" ""
			(at 0 0 90)
			(unlocked yes)
			(layer "B.Fab")
			(hide yes)
			(effects
				(font
					(size 1 1)
					(thickness 0.15)
				)
				(justify mirror)
			)
		)
		(property "Author" "Antmicro"
			(at 0 0 90)
			(unlocked yes)
			(layer "B.Fab")
			(hide yes)
			(effects
				(font
					(size 1 1)
					(thickness 0.15)
				)
				(justify mirror)
			)
		)
		(property "License" "Apache-2.0"
			(at 0 0 90)
			(unlocked yes)
			(layer "B.Fab")
			(hide yes)
			(effects
				(font
					(size 1 1)
					(thickness 0.15)
				)
				(justify mirror)
			)
		)
		(sheetname "/Peripherals/")
		(sheetfile "peripherals.kicad_sch")
		(attr exclude_from_pos_files exclude_from_bom)
		(fp_circle
			(center 0 0)
			(end 0.475 0)
			(stroke
				(width 0.05)
				(type default)
			)
			(fill no)
			(layer "B.CrtYd")
		)
		(fp_text user "${REFERENCE}"
			(at -0.4 -2.7 90)
			(layer "B.Fab")
			(effects
				(font
					(size 0.7 0.7)
					(thickness 0.15)
				)
				(justify left bottom mirror)
			)
		)
		(fp_text user "Author: Antmicro"
			(at -0.4 -3.901 90)
			(layer "B.Fab")
			(effects
				(font
					(size 0.7 0.7)
					(thickness 0.15)
				)
				(justify left bottom mirror)
			)
		)
		(fp_text user "License: Apache-2.0"
			(at -0.4 -5.101 90)
			(layer "B.Fab")
			(effects
				(font
					(size 0.7 0.7)
					(thickness 0.15)
				)
				(justify left bottom mirror)
			)
		)
		(pad "1" smd circle
			(at 0 0 270)
			(size 0.75 0.75)
			(layers "B.Cu" "B.Mask")
			(net 853 "/I2C_{SYS}.SCL")
			(pinfunction "1")
			(pintype "passive")
		)
	)
	(footprint "antmicro-footprints:R_0402_1005Metric"
		(layer "B.Cu")
		(at 62.2 66.5 -90)
		(descr "Resistor SMD 0402")
		(tags "resistor SMD 0402")
		(property "Reference" "R390"
			(at -9.7 0 90)
			(layer "B.SilkS")
			(effects
				(font
					(size 0.7 0.7)
					(thickness 0.15)
				)
				(justify left bottom mirror)
			)
		)
		(property "Value" "R_2k2_0402"
			(at -1.011843 -1.772047 90)
			(layer "B.Fab")
			(effects
				(font
					(size 0.7 0.7)
					(thickness 0.15)
				)
				(justify left bottom mirror)
			)
		)
		(property "Datasheet" "https://www.bourns.com/docs/product-datasheets/cr.pdf"
			(at 0 0 90)
			(layer "B.Fab")
			(hide yes)
			(effects
				(font
					(size 1.27 1.27)
					(thickness 0.15)
				)
				(justify mirror)
			)
		)
		(property "Description" "SMD Chip Resistor, 2.2 kohm, ± 1%, 62.5 mW, 0402 [1005 Metric], Thick Film, General Purpose"
			(at 0 0 90)
			(layer "B.Fab")
			(hide yes)
			(effects
				(font
					(size 1.27 1.27)
					(thickness 0.15)
				)
				(justify mirror)
			)
		)
		(property "MPN" "CR0402-FX-2201GLF"
			(at 0 0 90)
			(unlocked yes)
			(layer "B.Fab")
			(hide yes)
			(effects
				(font
					(size 1 1)
					(thickness 0.15)
				)
				(justify mirror)
			)
		)
		(property "Manufacturer" "Bourns"
			(at 0 0 90)
			(unlocked yes)
			(layer "B.Fab")
			(hide yes)
			(effects
				(font
					(size 1 1)
					(thickness 0.15)
				)
				(justify mirror)
			)
		)
		(property "License" "Apache-2.0"
			(at 0 0 90)
			(unlocked yes)
			(layer "B.Fab")
			(hide yes)
			(effects
				(font
					(size 1 1)
					(thickness 0.15)
				)
				(justify mirror)
			)
		)
		(property "Author" "Antmicro"
			(at 0 0 90)
			(unlocked yes)
			(layer "B.Fab")
			(hide yes)
			(effects
				(font
					(size 1 1)
					(thickness 0.15)
				)
				(justify mirror)
			)
		)
		(property "Val" "2k2"
			(at 0 0 90)
			(unlocked yes)
			(layer "B.Fab")
			(hide yes)
			(effects
				(font
					(size 1 1)
					(thickness 0.15)
				)
				(justify mirror)
			)
		)
		(property "Tolerance" "1%"
			(at 0 0 90)
			(unlocked yes)
			(layer "B.Fab")
			(hide yes)
			(effects
				(font
					(size 1 1)
					(thickness 0.15)
				)
				(justify mirror)
			)
		)
		(sheetname "/CSI/")
		(sheetfile "csi.kicad_sch")
		(attr smd)
		(fp_rect
			(start -0.925 0.47)
			(end 0.925 -0.47)
			(stroke
				(width 0.05)
				(type default)
			)
			(fill no)
			(layer "B.CrtYd")
		)
		(fp_rect
			(start -0.5 0.25)
			(end 0.5 -0.25)
			(stroke
				(width 0.15)
				(type solid)
			)
			(fill no)
			(layer "B.Fab")
		)
		(fp_text user "Author: Antmicro"
			(at -0.95 -4.169 90)
			(layer "B.Fab")
			(effects
				(font
					(size 0.7 0.7)
					(thickness 0.15)
				)
				(justify left bottom mirror)
			)
		)
		(fp_text user "${REFERENCE}"
			(at -0.95 -3.168 90)
			(layer "B.Fab")
			(effects
				(font
					(size 0.7 0.7)
					(thickness 0.15)
				)
				(justify left bottom mirror)
			)
		)
		(fp_text user "License: Apache-2.0"
			(at -0.95 -5.169 90)
			(layer "B.Fab")
			(effects
				(font
					(size 0.7 0.7)
					(thickness 0.15)
				)
				(justify left bottom mirror)
			)
		)
		(pad "1" smd roundrect
			(at -0.48 0 270)
			(size 0.59 0.64)
			(layers "B.Cu" "B.Mask" "B.Paste")
			(roundrect_rratio 0.25)
			(net 979 "/CSI/CSIA_I2C_VCC")
			(pintype "passive")
		)
		(pad "2" smd roundrect
			(at 0.48 0 270)
			(size 0.59 0.64)
			(layers "B.Cu" "B.Mask" "B.Paste")
			(roundrect_rratio 0.25)
			(net 985 "/CSI/SCL_CAM0")
			(pintype "passive")
		)
	)
	(footprint "antmicro-footprints:R_0402_1005Metric"
		(layer "B.Cu")
		(at 197.6 70.6 -90)
		(descr "Resistor SMD 0402")
		(tags "resistor SMD 0402")
		(property "Reference" "R104"
			(at -1.5 1.5 90)
			(layer "B.SilkS")
			(effects
				(font
					(size 0.7 0.7)
					(thickness 0.15)
				)
				(justify left bottom mirror)
			)
		)
		(property "Value" "R_4k7_0402"
			(at -1.011843 -1.772046 90)
			(layer "B.Fab")
			(effects
				(font
					(size 0.7 0.7)
					(thickness 0.15)
				)
				(justify left bottom mirror)
			)
		)
		(property "Datasheet" "https://www.bourns.com/docs/product-datasheets/cr.pdf"
			(at 0 0 90)
			(layer "B.Fab")
			(hide yes)
			(effects
				(font
					(size 1.27 1.27)
					(thickness 0.15)
				)
				(justify mirror)
			)
		)
		(property "Description" "SMD Chip Resistor, 4.7 kohm, ± 1%, 62.5 mW, 0402 [1005 Metric], Thick Film, General Purpose"
			(at 0 0 90)
			(layer "B.Fab")
			(hide yes)
			(effects
				(font
					(size 1.27 1.27)
					(thickness 0.15)
				)
				(justify mirror)
			)
		)
		(property "Manufacturer" "Bourns"
			(at 0 0 90)
			(unlocked yes)
			(layer "B.Fab")
			(hide yes)
			(effects
				(font
					(size 1 1)
					(thickness 0.15)
				)
				(justify mirror)
			)
		)
		(property "MPN" "CR0402-FX-4701GLF"
			(at 0 0 90)
			(unlocked yes)
			(layer "B.Fab")
			(hide yes)
			(effects
				(font
					(size 1 1)
					(thickness 0.15)
				)
				(justify mirror)
			)
		)
		(property "Val" "4k7"
			(at 0 0 90)
			(unlocked yes)
			(layer "B.Fab")
			(hide yes)
			(effects
				(font
					(size 1 1)
					(thickness 0.15)
				)
				(justify mirror)
			)
		)
		(property "License" "Apache-2.0"
			(at 0 0 90)
			(unlocked yes)
			(layer "B.Fab")
			(hide yes)
			(effects
				(font
					(size 1 1)
					(thickness 0.15)
				)
				(justify mirror)
			)
		)
		(property "Author" "Antmicro"
			(at 0 0 90)
			(unlocked yes)
			(layer "B.Fab")
			(hide yes)
			(effects
				(font
					(size 1 1)
					(thickness 0.15)
				)
				(justify mirror)
			)
		)
		(property "Tolerance" "1%"
			(at 0 0 90)
			(unlocked yes)
			(layer "B.Fab")
			(hide yes)
			(effects
				(font
					(size 1 1)
					(thickness 0.15)
				)
				(justify mirror)
			)
		)
		(sheetname "/USB Debug, PD/")
		(sheetfile "usb_debug_pd.kicad_sch")
		(attr smd exclude_from_pos_files exclude_from_bom dnp)
		(fp_poly
			(pts
				(xy -0.925 0.47) (xy 0.925 0.47) (xy 0.925 -0.47) (xy -0.925 -0.47)
			)
			(stroke
				(width 0.05)
				(type default)
			)
			(fill no)
			(layer "B.CrtYd")
		)
		(fp_poly
			(pts
				(xy -0.5 0.25) (xy 0.5 0.25) (xy 0.5 -0.25) (xy -0.5 -0.25)
			)
			(stroke
				(width 0.15)
				(type solid)
			)
			(fill no)
			(layer "B.Fab")
		)
		(fp_text user "License: Apache-2.0"
			(at -0.949999 -5.169 90)
			(layer "B.Fab")
			(effects
				(font
					(size 0.7 0.7)
					(thickness 0.15)
				)
				(justify left bottom mirror)
			)
		)
		(fp_text user "Author: Antmicro"
			(at -0.95 -4.169 90)
			(layer "B.Fab")
			(effects
				(font
					(size 0.7 0.7)
					(thickness 0.15)
				)
				(justify left bottom mirror)
			)
		)
		(fp_text user "${REFERENCE}"
			(at -0.95 -3.168 90)
			(layer "B.Fab")
			(effects
				(font
					(size 0.7 0.7)
					(thickness 0.15)
				)
				(justify left bottom mirror)
			)
		)
		(pad "1" smd roundrect
			(at -0.48 0 270)
			(size 0.59 0.64)
			(layers "B.Cu" "B.Mask" "B.Paste")
			(roundrect_rratio 0.25)
			(net 2 "+3V3")
			(pintype "passive")
		)
		(pad "2" smd roundrect
			(at 0.48 0 270)
			(size 0.59 0.64)
			(layers "B.Cu" "B.Mask" "B.Paste")
			(roundrect_rratio 0.25)
			(net 946 "/USB Debug, PD/DEBUG_SDA")
			(pintype "passive")
		)
	)
)
